# T6G (Grand Teton) — schematic netlist excerpt (pin names and nets, part order shuffled) for the footprints in the layout excerpt that follows; sources: Cadence DE-HDL packaged netlist, KiCad conversion of 04192023_DAF0TMB3IC0_F0TG_MB_C_brd_V02_OCP.brd

R127  Q_RES  1K 1% EMPTY  pkg 0402LF  page 77 : A = P3V3_AUX ; B = SPI_CPU0_LVC3_SCM_D1
PR134  Q_RES  4.87K 1% EMPTY  pkg 0402LF  page 208 : A = GND ; B = PVDD11_S3_P0_LSET2

U166  SCHOTTKY_DUAL_12A_3C  BAT54CW IC  pkg SOT323  page 187
  B  = P3V3_STBY_R
  A  = P3V_BAT_R
  C  = P3V3_RTC_AUX

(kicad_pcb
	(version 20260206)
	(generator "pcbnew")
	(generator_version "10.0")
	(general
		(thickness 1.6)
		(legacy_teardrops no)
	)
	(paper "A4")
	(title_block
		(title "04192023_DAF0TMB3IC0_F0TG_MB_C_brd_V02_OCP.brd")
		(comment 1 "Grand Teton / footprints 1943-1945 of 8354")
	)
	(layers
		(0 "F.Cu" signal "TOP")
		(4 "In1.Cu" signal "GND")
		(6 "In2.Cu" signal "IN1")
		(8 "In3.Cu" signal "GND1")
		(10 "In4.Cu" signal "IN2")
		(12 "In5.Cu" signal "GND2")
		(14 "In6.Cu" signal "IN3")
		(16 "In7.Cu" signal "GND3")
		(18 "In8.Cu" signal "VCC")
		(20 "In9.Cu" signal "VCC1")
		(22 "In10.Cu" signal "GND4")
		(24 "In11.Cu" signal "IN4")
		(26 "In12.Cu" signal "GND5")
		(28 "In13.Cu" signal "IN5")
		(30 "In14.Cu" signal "GND6")
		(32 "In15.Cu" signal "IN6")
		(34 "In16.Cu" signal "GND7")
		(2 "B.Cu" signal "BOTTOM")
		(9 "F.Adhes" user "F.Adhesive")
		(11 "B.Adhes" user "B.Adhesive")
		(13 "F.Paste" user "Package Geometry/Pastemask Top")
		(15 "B.Paste" user "Package Geometry/Pastemask Bottom")
		(5 "F.SilkS" user "Ref Des/Silkscreen Top")
		(7 "B.SilkS" user "Ref Des/Silkscreen Bottom")
		(1 "F.Mask" user "Board Geometry/Soldermask Top")
		(3 "B.Mask" user "Board Geometry/Soldermask Bottom")
		(17 "Dwgs.User" user "User.Drawings")
		(19 "Cmts.User" user "User.Comments")
		(21 "Eco1.User" user "User.Eco1")
		(23 "Eco2.User" user "User.Eco2")
		(25 "Edge.Cuts" user "Board Geometry/Outline")
		(27 "Margin" user)
		(31 "F.CrtYd" user "Package Geometry/Place Bound Top")
		(29 "B.CrtYd" user "Package Geometry/Place Bound Bottom")
		(35 "F.Fab" user "Ref Des/Assembly Top")
		(33 "B.Fab" user "Ref Des/Assembly Bottom")
	)
	(footprint ""
		(layer "F.Cu")
		(at 259.842 -143.764)
		(property "Reference" "R127"
			(at 0 0 0)
			(layer "F.SilkS")
			(hide yes)
			(effects
				(font
					(size 1.27 1.27)
				)
			)
		)
		(property "Value" ""
			(at 0 0 0)
			(layer "F.Fab")
			(effects
				(font
					(size 1.27 1.27)
				)
			)
		)
		(duplicate_pad_numbers_are_jumpers no)
		(fp_line
			(start -0.7874 -0.4064)
			(end 0.7874 -0.4064)
			(stroke
				(width 0.1524)
				(type default)
			)
			(layer "F.SilkS")
		)
		(fp_line
			(start -0.7874 0.4064)
			(end -0.7874 -0.4064)
			(stroke
				(width 0.1524)
				(type default)
			)
			(layer "F.SilkS")
		)
		(fp_line
			(start 0.7874 -0.4064)
			(end 0.7874 0.4064)
			(stroke
				(width 0.1524)
				(type default)
			)
			(layer "F.SilkS")
		)
		(fp_line
			(start 0.7874 0.4064)
			(end -0.7874 0.4064)
			(stroke
				(width 0.1524)
				(type default)
			)
			(layer "F.SilkS")
		)
		(fp_line
			(start -0.67945 -0.305054)
			(end -0.12065 -0.305054)
			(stroke
				(width 0.1)
				(type default)
			)
			(layer "F.Fab")
		)
		(fp_line
			(start -0.67945 0.3048)
			(end -0.67945 -0.305054)
			(stroke
				(width 0.1)
				(type default)
			)
			(layer "F.Fab")
		)
		(fp_line
			(start -0.12065 -0.305054)
			(end -0.12065 -0.2794)
			(stroke
				(width 0.1)
				(type default)
			)
			(layer "F.Fab")
		)
		(fp_line
			(start -0.12065 -0.2794)
			(end 0.12065 -0.2794)
			(stroke
				(width 0.1)
				(type default)
			)
			(layer "F.Fab")
		)
		(fp_line
			(start -0.12065 0.2794)
			(end -0.12065 0.3048)
			(stroke
				(width 0.1)
				(type default)
			)
			(layer "F.Fab")
		)
		(fp_line
			(start -0.12065 0.3048)
			(end -0.67945 0.3048)
			(stroke
				(width 0.1)
				(type default)
			)
			(layer "F.Fab")
		)
		(fp_line
			(start 0.120396 0.2794)
			(end -0.12065 0.2794)
			(stroke
				(width 0.1)
				(type default)
			)
			(layer "F.Fab")
		)
		(fp_line
			(start 0.120396 0.3048)
			(end 0.120396 0.2794)
			(stroke
				(width 0.1)
				(type default)
			)
			(layer "F.Fab")
		)
		(fp_line
			(start 0.12065 -0.3048)
			(end 0.67945 -0.3048)
			(stroke
				(width 0.1)
				(type default)
			)
			(layer "F.Fab")
		)
		(fp_line
			(start 0.12065 -0.2794)
			(end 0.12065 -0.3048)
			(stroke
				(width 0.1)
				(type default)
			)
			(layer "F.Fab")
		)
		(fp_line
			(start 0.67945 -0.3048)
			(end 0.67945 0.3048)
			(stroke
				(width 0.1)
				(type default)
			)
			(layer "F.Fab")
		)
		(fp_line
			(start 0.67945 0.3048)
			(end 0.120396 0.3048)
			(stroke
				(width 0.1)
				(type default)
			)
			(layer "F.Fab")
		)
		(pad "1" smd circle
			(at -0.40005 0)
			(size 0 0)
			(layers "F.Cu" "F.Mask" "F.Paste")
			(net "P3V3_AUX")
		)
		(pad "2" smd circle
			(at 0.40005 0)
			(size 0 0)
			(layers "F.Cu" "F.Mask" "F.Paste")
			(net "SPI_CPU0_LVC3_SCM_D1")
		)
	)
	(footprint ""
		(layer "F.Cu")
		(at 430.666144 -356.35184 180)
		(property "Reference" "PR134"
			(at 0 0 180)
			(layer "F.SilkS")
			(hide yes)
			(effects
				(font
					(size 1.27 1.27)
				)
			)
		)
		(property "Value" ""
			(at 0 0 180)
			(layer "F.Fab")
			(effects
				(font
					(size 1.27 1.27)
				)
			)
		)
		(duplicate_pad_numbers_are_jumpers no)
		(fp_line
			(start 0.7874 0.4064)
			(end -0.7874 0.4064)
			(stroke
				(width 0.1524)
				(type default)
			)
			(layer "F.SilkS")
		)
		(fp_line
			(start 0.7874 -0.4064)
			(end 0.7874 0.4064)
			(stroke
				(width 0.1524)
				(type default)
			)
			(layer "F.SilkS")
		)
		(fp_line
			(start -0.7874 0.4064)
			(end -0.7874 -0.4064)
			(stroke
				(width 0.1524)
				(type default)
			)
			(layer "F.SilkS")
		)
		(fp_line
			(start -0.7874 -0.4064)
			(end 0.7874 -0.4064)
			(stroke
				(width 0.1524)
				(type default)
			)
			(layer "F.SilkS")
		)
		(fp_line
			(start 0.67945 0.3048)
			(end 0.120396 0.3048)
			(stroke
				(width 0.1)
				(type default)
			)
			(layer "F.Fab")
		)
		(fp_line
			(start 0.67945 -0.3048)
			(end 0.67945 0.3048)
			(stroke
				(width 0.1)
				(type default)
			)
			(layer "F.Fab")
		)
		(fp_line
			(start 0.12065 -0.2794)
			(end 0.12065 -0.3048)
			(stroke
				(width 0.1)
				(type default)
			)
			(layer "F.Fab")
		)
		(fp_line
			(start 0.12065 -0.3048)
			(end 0.67945 -0.3048)
			(stroke
				(width 0.1)
				(type default)
			)
			(layer "F.Fab")
		)
		(fp_line
			(start 0.120396 0.3048)
			(end 0.120396 0.2794)
			(stroke
				(width 0.1)
				(type default)
			)
			(layer "F.Fab")
		)
		(fp_line
			(start 0.120396 0.2794)
			(end -0.12065 0.2794)
			(stroke
				(width 0.1)
				(type default)
			)
			(layer "F.Fab")
		)
		(fp_line
			(start -0.12065 0.3048)
			(end -0.67945 0.3048)
			(stroke
				(width 0.1)
				(type default)
			)
			(layer "F.Fab")
		)
		(fp_line
			(start -0.12065 0.2794)
			(end -0.12065 0.3048)
			(stroke
				(width 0.1)
				(type default)
			)
			(layer "F.Fab")
		)
		(fp_line
			(start -0.12065 -0.2794)
			(end 0.12065 -0.2794)
			(stroke
				(width 0.1)
				(type default)
			)
			(layer "F.Fab")
		)
		(fp_line
			(start -0.12065 -0.305054)
			(end -0.12065 -0.2794)
			(stroke
				(width 0.1)
				(type default)
			)
			(layer "F.Fab")
		)
		(fp_line
			(start -0.67945 0.3048)
			(end -0.67945 -0.305054)
			(stroke
				(width 0.1)
				(type default)
			)
			(layer "F.Fab")
		)
		(fp_line
			(start -0.67945 -0.305054)
			(end -0.12065 -0.305054)
			(stroke
				(width 0.1)
				(type default)
			)
			(layer "F.Fab")
		)
		(pad "1" smd circle
			(at -0.40005 0 180)
			(size 0 0)
			(layers "F.Cu" "F.Mask" "F.Paste")
			(net "GND")
		)
		(pad "2" smd circle
			(at 0.40005 0 180)
			(size 0 0)
			(layers "F.Cu" "F.Mask" "F.Paste")
			(net "PVDD11_S3_P0_LSET2")
		)
	)
	(footprint ""
		(layer "F.Cu")
		(at 308.528974 -33.351978)
		(property "Reference" "U166"
			(at -1.4224 -1.844548 0)
			(unlocked yes)
			(layer "F.SilkS")
			(effects
				(font
					(size 0.7874 0.5842)
					(thickness 0.1524)
				)
				(justify left)
			)
		)
		(property "Value" ""
			(at 0 0 0)
			(layer "F.Fab")
			(effects
				(font
					(size 1.27 1.27)
				)
			)
		)
		(duplicate_pad_numbers_are_jumpers no)
		(fp_line
			(start -1.335278 -1.100074)
			(end -1.335278 1.100074)
			(stroke
				(width 0.1524)
				(type default)
			)
			(layer "F.SilkS")
		)
		(fp_line
			(start -1.335278 1.100074)
			(end 1.335278 1.100074)
			(stroke
				(width 0.1524)
				(type default)
			)
			(layer "F.SilkS")
		)
		(fp_line
			(start 1.335278 -1.100074)
			(end -1.335278 -1.100074)
			(stroke
				(width 0.1524)
				(type default)
			)
			(layer "F.SilkS")
		)
		(fp_line
			(start 1.335278 1.100074)
			(end 1.335278 -1.100074)
			(stroke
				(width 0.1524)
				(type default)
			)
			(layer "F.SilkS")
		)
		(fp_line
			(start -0.674878 -1.100074)
			(end -0.674878 1.100074)
			(stroke
				(width 0.1)
				(type default)
			)
			(layer "F.Fab")
		)
		(fp_line
			(start -0.674878 1.100074)
			(end 0.674878 1.100074)
			(stroke
				(width 0.1)
				(type default)
			)
			(layer "F.Fab")
		)
		(fp_line
			(start 0.674878 -1.100074)
			(end -0.674878 -1.100074)
			(stroke
				(width 0.1)
				(type default)
			)
			(layer "F.Fab")
		)
		(fp_line
			(start 0.674878 1.100074)
			(end 0.674878 -1.100074)
			(stroke
				(width 0.1)
				(type default)
			)
			(layer "F.Fab")
		)
		(pad "1" smd rect
			(at -0.8001 0.649986 270)
			(size 0.6096 0.8128)
			(layers "F.Cu" "F.Mask" "F.Paste")
			(net "P3V3_STBY_R")
		)
		(pad "2" smd rect
			(at -0.8001 -0.649986 270)
			(size 0.6096 0.8128)
			(layers "F.Cu" "F.Mask" "F.Paste")
			(net "P3V_BAT_R")
		)
		(pad "3" smd rect
			(at 0.8001 0 270)
			(size 0.6096 0.8128)
			(layers "F.Cu" "F.Mask" "F.Paste")
			(net "P3V3_RTC_AUX")
		)
	)
)
